(kicad_pcb
	(version 20260206)
	(generator "pcbnew")
	(generator_version "10.0")
	(general
		(thickness 1.6)
		(legacy_teardrops no)
	)
	(paper "A4")
	(title_block
		(title "Wiwynn_Tioga_Pass_MB.brd")
		(comment 1 "Tioga Pass / footprints 903-910 of 4770")
	)
	(layers
		(0 "F.Cu" signal "TOP")
		(4 "In1.Cu" signal "L2GND")
		(6 "In2.Cu" signal "L3")
		(8 "In3.Cu" signal "L4GND")
		(10 "In4.Cu" signal "L5")
		(12 "In5.Cu" signal "L6GND")
		(14 "In6.Cu" signal "L7VCC")
		(16 "In7.Cu" signal "L8VCC")
		(18 "In8.Cu" signal "L9GND")
		(20 "In9.Cu" signal "L10")
		(22 "In10.Cu" signal "L11GND")
		(24 "In11.Cu" signal "L12")
		(26 "In12.Cu" signal "L13GND")
		(2 "B.Cu" signal "BOTTOM")
		(9 "F.Adhes" user "F.Adhesive")
		(11 "B.Adhes" user "B.Adhesive")
		(13 "F.Paste" user "Package Geometry/Pastemask Top")
		(15 "B.Paste" user "Package Geometry/Pastemask Bottom")
		(5 "F.SilkS" user "Ref Des/Silkscreen Top")
		(7 "B.SilkS" user "Ref Des/Silkscreen Bottom")
		(1 "F.Mask" user "Board Geometry/Soldermask Top")
		(3 "B.Mask" user "Board Geometry/Soldermask Bottom")
		(17 "Dwgs.User" user "User.Drawings")
		(19 "Cmts.User" user "User.Comments")
		(21 "Eco1.User" user "User.Eco1")
		(23 "Eco2.User" user "User.Eco2")
		(25 "Edge.Cuts" user "Board Geometry/Outline")
		(27 "Margin" user)
		(31 "F.CrtYd" user "Package Geometry/Place Bound Top")
		(29 "B.CrtYd" user "Package Geometry/Place Bound Bottom")
		(35 "F.Fab" user "Ref Des/Assembly Top")
		(33 "B.Fab" user "Ref Des/Assembly Bottom")
	)
	(footprint ""
		(layer "F.Cu")
		(at 482.6508 -32.2834)
		(property "Reference" "C8F18"
			(at 0 0 0)
			(layer "F.SilkS")
			(hide yes)
			(effects
				(font
					(size 1.27 1.27)
				)
			)
		)
		(property "Value" ""
			(at 0 0 0)
			(layer "F.Fab")
			(effects
				(font
					(size 1.27 1.27)
				)
			)
		)
		(duplicate_pad_numbers_are_jumpers no)
		(fp_poly
			(pts
				(xy 0.3048 -0.1016) (xy 0.3048 0.9906) (xy -0.3048 0.9906) (xy -0.3048 -0.1016)
			)
			(stroke
				(width 0)
				(type default)
			)
			(fill no)
			(layer "F.CrtYd")
		)
		(fp_line
			(start -0.3048 -0.1016)
			(end -0.3048 0.9906)
			(stroke
				(width 0.1)
				(type default)
			)
			(layer "F.Fab")
		)
		(fp_line
			(start -0.3048 0.9906)
			(end 0.3048 0.9906)
			(stroke
				(width 0.1)
				(type default)
			)
			(layer "F.Fab")
		)
		(fp_line
			(start 0.3048 -0.1016)
			(end -0.3048 -0.1016)
			(stroke
				(width 0.1)
				(type default)
			)
			(layer "F.Fab")
		)
		(fp_line
			(start 0.3048 0.9906)
			(end 0.3048 -0.1016)
			(stroke
				(width 0.1)
				(type default)
			)
			(layer "F.Fab")
		)
		(pad "1" smd rect
			(at 0 0)
			(size 0.508 0.508)
			(layers "F.Cu" "F.Mask" "F.Paste")
			(net "XTAL_CK_MNG_IN")
		)
		(pad "2" smd rect
			(at 0 0.889)
			(size 0.508 0.508)
			(layers "F.Cu" "F.Mask" "F.Paste")
			(net "GND")
		)
		(zone
			(layer "F.Cu")
			(hatch none 0.5)
			(connect_pads
				(clearance 0)
			)
			(min_thickness 0.25)
			(keepout
				(tracks allowed)
				(vias not_allowed)
				(pads allowed)
				(copperpour not_allowed)
				(footprints allowed)
			)
			(placement
				(enabled no)
				(sheetname "")
			)
			(fill
				(thermal_gap 0.5)
				(thermal_bridge_width 0.5)
				(island_removal_mode 0)
			)
			(polygon
				(pts
					(xy 482.3968 -32.0294) (xy 482.9048 -32.0294) (xy 482.9048 -31.6484) (xy 482.3968 -31.6484)
				)
			)
		)
		(zone
			(layer "F.Cu")
			(hatch none 0.5)
			(connect_pads
				(clearance 0)
			)
			(min_thickness 0.25)
			(keepout
				(tracks not_allowed)
				(vias allowed)
				(pads allowed)
				(copperpour not_allowed)
				(footprints allowed)
			)
			(placement
				(enabled no)
				(sheetname "")
			)
			(fill
				(thermal_gap 0.5)
				(thermal_bridge_width 0.5)
				(island_removal_mode 0)
			)
			(polygon
				(pts
					(xy 482.3968 -31.6484) (xy 482.9048 -31.6484) (xy 482.9048 -32.0294) (xy 482.3968 -32.0294)
				)
			)
		)
	)
	(footprint ""
		(layer "F.Cu")
		(at 93.20784 -77.636116)
		(property "Reference" "C2D19"
			(at 0 0 0)
			(layer "F.SilkS")
			(hide yes)
			(effects
				(font
					(size 1.27 1.27)
				)
			)
		)
		(property "Value" ""
			(at 0 0 0)
			(layer "F.Fab")
			(effects
				(font
					(size 1.27 1.27)
				)
			)
		)
		(duplicate_pad_numbers_are_jumpers no)
		(fp_poly
			(pts
				(xy -0.4953 -0.2032) (xy 0.4953 -0.2032) (xy 0.4953 1.6002) (xy -0.4953 1.6002)
			)
			(stroke
				(width 0)
				(type default)
			)
			(fill no)
			(layer "F.CrtYd")
		)
		(fp_line
			(start -0.4953 -0.2032)
			(end 0.4953 -0.2032)
			(stroke
				(width 0.1)
				(type default)
			)
			(layer "F.Fab")
		)
		(fp_line
			(start -0.4953 1.6002)
			(end -0.4953 -0.2032)
			(stroke
				(width 0.1)
				(type default)
			)
			(layer "F.Fab")
		)
		(fp_line
			(start 0.4953 -0.2032)
			(end 0.4953 1.6002)
			(stroke
				(width 0.1)
				(type default)
			)
			(layer "F.Fab")
		)
		(fp_line
			(start 0.4953 1.6002)
			(end -0.4953 1.6002)
			(stroke
				(width 0.1)
				(type default)
			)
			(layer "F.Fab")
		)
		(pad "1" smd rect
			(at 0 0)
			(size 0.762 0.889)
			(layers "F.Cu" "F.Mask" "F.Paste")
			(net "PVCCIN_CPU1")
		)
		(pad "2" smd rect
			(at 0 1.397)
			(size 0.762 0.889)
			(layers "F.Cu" "F.Mask" "F.Paste")
			(net "GND")
		)
		(zone
			(layer "F.Cu")
			(hatch none 0.5)
			(connect_pads
				(clearance 0)
			)
			(min_thickness 0.25)
			(keepout
				(tracks not_allowed)
				(vias allowed)
				(pads allowed)
				(copperpour not_allowed)
				(footprints allowed)
			)
			(placement
				(enabled no)
				(sheetname "")
			)
			(fill
				(thermal_gap 0.5)
				(thermal_bridge_width 0.5)
				(island_removal_mode 0)
			)
			(polygon
				(pts
					(xy 92.82684 -77.191616) (xy 93.58884 -77.191616) (xy 93.58884 -76.683616) (xy 92.82684 -76.683616)
				)
			)
		)
	)
	(footprint ""
		(layer "F.Cu")
		(at 491.0455 -43.0784 90)
		(property "Reference" "R9E17"
			(at 0 0 90)
			(layer "F.SilkS")
			(hide yes)
			(effects
				(font
					(size 1.27 1.27)
				)
			)
		)
		(property "Value" ""
			(at 0 0 90)
			(layer "F.Fab")
			(effects
				(font
					(size 1.27 1.27)
				)
			)
		)
		(duplicate_pad_numbers_are_jumpers no)
		(fp_poly
			(pts
				(xy -0.2794 -0.1016) (xy 0.2794 -0.1016) (xy 0.2794 0.9906) (xy -0.2794 0.9906)
			)
			(stroke
				(width 0)
				(type default)
			)
			(fill no)
			(layer "F.CrtYd")
		)
		(fp_line
			(start 0.2794 -0.1016)
			(end -0.2794 -0.1016)
			(stroke
				(width 0.1)
				(type default)
			)
			(layer "F.Fab")
		)
		(fp_line
			(start -0.2794 -0.1016)
			(end -0.2794 0.9906)
			(stroke
				(width 0.1)
				(type default)
			)
			(layer "F.Fab")
		)
		(fp_line
			(start 0.2794 0.9906)
			(end 0.2794 -0.1016)
			(stroke
				(width 0.1)
				(type default)
			)
			(layer "F.Fab")
		)
		(fp_line
			(start -0.2794 0.9906)
			(end 0.2794 0.9906)
			(stroke
				(width 0.1)
				(type default)
			)
			(layer "F.Fab")
		)
		(pad "1" smd rect
			(at 0 0 90)
			(size 0.508 0.508)
			(layers "F.Cu" "F.Mask" "F.Paste")
			(net "RMII_SPRNGVLLE_BMC_PCH_RXD0_R")
		)
		(pad "2" smd rect
			(at 0 0.889 90)
			(size 0.508 0.508)
			(layers "F.Cu" "F.Mask" "F.Paste")
			(net "RMII_SPRNGVLLE_BMC_PCH_RXD0")
		)
		(zone
			(layer "F.Cu")
			(hatch none 0.5)
			(connect_pads
				(clearance 0)
			)
			(min_thickness 0.25)
			(keepout
				(tracks allowed)
				(vias not_allowed)
				(pads allowed)
				(copperpour not_allowed)
				(footprints allowed)
			)
			(placement
				(enabled no)
				(sheetname "")
			)
			(fill
				(thermal_gap 0.5)
				(thermal_bridge_width 0.5)
				(island_removal_mode 0)
			)
			(polygon
				(pts
					(xy 491.2995 -42.8244) (xy 491.2995 -43.3324) (xy 491.6805 -43.3324) (xy 491.6805 -42.8244)
				)
			)
		)
		(zone
			(layer "F.Cu")
			(hatch none 0.5)
			(connect_pads
				(clearance 0)
			)
			(min_thickness 0.25)
			(keepout
				(tracks not_allowed)
				(vias allowed)
				(pads allowed)
				(copperpour not_allowed)
				(footprints allowed)
			)
			(placement
				(enabled no)
				(sheetname "")
			)
			(fill
				(thermal_gap 0.5)
				(thermal_bridge_width 0.5)
				(island_removal_mode 0)
			)
			(polygon
				(pts
					(xy 491.6805 -42.8244) (xy 491.6805 -43.3324) (xy 491.2995 -43.3324) (xy 491.2995 -42.8244)
				)
			)
		)
	)
	(footprint ""
		(layer "F.Cu")
		(at 465.582 -20.4343 180)
		(property "Reference" "R8F5"
			(at 0 0 180)
			(layer "F.SilkS")
			(hide yes)
			(effects
				(font
					(size 1.27 1.27)
				)
			)
		)
		(property "Value" ""
			(at 0 0 180)
			(layer "F.Fab")
			(effects
				(font
					(size 1.27 1.27)
				)
			)
		)
		(duplicate_pad_numbers_are_jumpers no)
		(fp_rect
			(start -0.2794 -0.1016)
			(end 0.2794 0.9906)
			(stroke
				(width 0)
				(type default)
			)
			(fill no)
			(layer "F.CrtYd")
		)
		(fp_line
			(start 0.2794 0.9906)
			(end 0.2794 -0.1016)
			(stroke
				(width 0.1)
				(type default)
			)
			(layer "F.Fab")
		)
		(fp_line
			(start 0.2794 -0.1016)
			(end -0.2794 -0.1016)
			(stroke
				(width 0.1)
				(type default)
			)
			(layer "F.Fab")
		)
		(fp_line
			(start -0.2794 0.9906)
			(end 0.2794 0.9906)
			(stroke
				(width 0.1)
				(type default)
			)
			(layer "F.Fab")
		)
		(fp_line
			(start -0.2794 -0.1016)
			(end -0.2794 0.9906)
			(stroke
				(width 0.1)
				(type default)
			)
			(layer "F.Fab")
		)
		(pad "1" smd rect
			(at 0 0 180)
			(size 0.508 0.508)
			(layers "F.Cu" "F.Mask" "F.Paste")
			(net "P3V3_STBY")
		)
		(pad "2" smd rect
			(at 0 0.889 180)
			(size 0.508 0.508)
			(layers "F.Cu" "F.Mask" "F.Paste")
			(net "PWRGD_P3V3_STBY_R")
		)
		(zone
			(layer "F.Cu")
			(hatch none 0.5)
			(connect_pads
				(clearance 0)
			)
			(min_thickness 0.25)
			(keepout
				(tracks not_allowed)
				(vias allowed)
				(pads allowed)
				(copperpour not_allowed)
				(footprints allowed)
			)
			(placement
				(enabled no)
				(sheetname "")
			)
			(fill
				(thermal_gap 0.5)
				(thermal_bridge_width 0.5)
				(island_removal_mode 0)
			)
			(polygon
				(pts
					(xy 465.836 -20.6883) (xy 465.836 -21.0693) (xy 465.328 -21.0693) (xy 465.328 -20.6883)
				)
			)
		)
		(zone
			(layer "F.Cu")
			(hatch none 0.5)
			(connect_pads
				(clearance 0)
			)
			(min_thickness 0.25)
			(keepout
				(tracks allowed)
				(vias not_allowed)
				(pads allowed)
				(copperpour not_allowed)
				(footprints allowed)
			)
			(placement
				(enabled no)
				(sheetname "")
			)
			(fill
				(thermal_gap 0.5)
				(thermal_bridge_width 0.5)
				(island_removal_mode 0)
			)
			(polygon
				(pts
					(xy 465.836 -20.6883) (xy 465.836 -21.0693) (xy 465.328 -21.0693) (xy 465.328 -20.6883)
				)
			)
		)
	)
	(footprint ""
		(layer "F.Cu")
		(at 368.554 -110.998 90)
		(property "Reference" "C7C2"
			(at 0 0 90)
			(layer "F.SilkS")
			(hide yes)
			(effects
				(font
					(size 1.27 1.27)
				)
			)
		)
		(property "Value" ""
			(at 0 0 90)
			(layer "F.Fab")
			(effects
				(font
					(size 1.27 1.27)
				)
			)
		)
		(duplicate_pad_numbers_are_jumpers no)
		(fp_poly
			(pts
				(xy 0.3048 -0.1016) (xy 0.3048 0.9906) (xy -0.3048 0.9906) (xy -0.3048 -0.1016)
			)
			(stroke
				(width 0)
				(type default)
			)
			(fill no)
			(layer "F.CrtYd")
		)
		(fp_line
			(start 0.3048 -0.1016)
			(end -0.3048 -0.1016)
			(stroke
				(width 0.1)
				(type default)
			)
			(layer "F.Fab")
		)
		(fp_line
			(start -0.3048 -0.1016)
			(end -0.3048 0.9906)
			(stroke
				(width 0.1)
				(type default)
			)
			(layer "F.Fab")
		)
		(fp_line
			(start 0.3048 0.9906)
			(end 0.3048 -0.1016)
			(stroke
				(width 0.1)
				(type default)
			)
			(layer "F.Fab")
		)
		(fp_line
			(start -0.3048 0.9906)
			(end 0.3048 0.9906)
			(stroke
				(width 0.1)
				(type default)
			)
			(layer "F.Fab")
		)
		(pad "1" smd rect
			(at 0 0 90)
			(size 0.508 0.508)
			(layers "F.Cu" "F.Mask" "F.Paste")
			(net "DMI_CPU0_PCH_TX_DP<0>")
		)
		(pad "2" smd rect
			(at 0 0.889 90)
			(size 0.508 0.508)
			(layers "F.Cu" "F.Mask" "F.Paste")
			(net "DMI_CPU0_PCH_TX_C_DP<0>")
		)
		(zone
			(layer "F.Cu")
			(hatch none 0.5)
			(connect_pads
				(clearance 0)
			)
			(min_thickness 0.25)
			(keepout
				(tracks allowed)
				(vias not_allowed)
				(pads allowed)
				(copperpour not_allowed)
				(footprints allowed)
			)
			(placement
				(enabled no)
				(sheetname "")
			)
			(fill
				(thermal_gap 0.5)
				(thermal_bridge_width 0.5)
				(island_removal_mode 0)
			)
			(polygon
				(pts
					(xy 368.808 -110.744) (xy 368.808 -111.252) (xy 369.189 -111.252) (xy 369.189 -110.744)
				)
			)
		)
		(zone
			(layer "F.Cu")
			(hatch none 0.5)
			(connect_pads
				(clearance 0)
			)
			(min_thickness 0.25)
			(keepout
				(tracks not_allowed)
				(vias allowed)
				(pads allowed)
				(copperpour not_allowed)
				(footprints allowed)
			)
			(placement
				(enabled no)
				(sheetname "")
			)
			(fill
				(thermal_gap 0.5)
				(thermal_bridge_width 0.5)
				(island_removal_mode 0)
			)
			(polygon
				(pts
					(xy 369.189 -110.744) (xy 369.189 -111.252) (xy 368.808 -111.252) (xy 368.808 -110.744)
				)
			)
		)
	)
	(footprint ""
		(layer "F.Cu")
		(at 364.78464 -141.77137)
		(property "Reference" "R7A7"
			(at 0 0 0)
			(layer "F.SilkS")
			(hide yes)
			(effects
				(font
					(size 1.27 1.27)
				)
			)
		)
		(property "Value" ""
			(at 0 0 0)
			(layer "F.Fab")
			(effects
				(font
					(size 1.27 1.27)
				)
			)
		)
		(duplicate_pad_numbers_are_jumpers no)
		(fp_poly
			(pts
				(xy -0.2794 -0.1016) (xy 0.2794 -0.1016) (xy 0.2794 0.9906) (xy -0.2794 0.9906)
			)
			(stroke
				(width 0)
				(type default)
			)
			(fill no)
			(layer "F.CrtYd")
		)
		(fp_line
			(start -0.2794 -0.1016)
			(end -0.2794 0.9906)
			(stroke
				(width 0.1)
				(type default)
			)
			(layer "F.Fab")
		)
		(fp_line
			(start -0.2794 0.9906)
			(end 0.2794 0.9906)
			(stroke
				(width 0.1)
				(type default)
			)
			(layer "F.Fab")
		)
		(fp_line
			(start 0.2794 -0.1016)
			(end -0.2794 -0.1016)
			(stroke
				(width 0.1)
				(type default)
			)
			(layer "F.Fab")
		)
		(fp_line
			(start 0.2794 0.9906)
			(end 0.2794 -0.1016)
			(stroke
				(width 0.1)
				(type default)
			)
			(layer "F.Fab")
		)
		(pad "1" smd rect
			(at 0 0)
			(size 0.508 0.508)
			(layers "F.Cu" "F.Mask" "F.Paste")
			(net "VSENSE_PVDDQ_DEF_P")
		)
		(pad "2" smd rect
			(at 0 0.889)
			(size 0.508 0.508)
			(layers "F.Cu" "F.Mask" "F.Paste")
			(net "VR_PVDDQ_DEF_AVSP")
		)
		(zone
			(layer "F.Cu")
			(hatch none 0.5)
			(connect_pads
				(clearance 0)
			)
			(min_thickness 0.25)
			(keepout
				(tracks allowed)
				(vias not_allowed)
				(pads allowed)
				(copperpour not_allowed)
				(footprints allowed)
			)
			(placement
				(enabled no)
				(sheetname "")
			)
			(fill
				(thermal_gap 0.5)
				(thermal_bridge_width 0.5)
				(island_removal_mode 0)
			)
			(polygon
				(pts
					(xy 364.53064 -141.51737) (xy 365.03864 -141.51737) (xy 365.03864 -141.13637) (xy 364.53064 -141.13637)
				)
			)
		)
		(zone
			(layer "F.Cu")
			(hatch none 0.5)
			(connect_pads
				(clearance 0)
			)
			(min_thickness 0.25)
			(keepout
				(tracks not_allowed)
				(vias allowed)
				(pads allowed)
				(copperpour not_allowed)
				(footprints allowed)
			)
			(placement
				(enabled no)
				(sheetname "")
			)
			(fill
				(thermal_gap 0.5)
				(thermal_bridge_width 0.5)
				(island_removal_mode 0)
			)
			(polygon
				(pts
					(xy 364.53064 -141.13637) (xy 365.03864 -141.13637) (xy 365.03864 -141.51737) (xy 364.53064 -141.51737)
				)
			)
		)
	)
	(footprint ""
		(layer "F.Cu")
		(at 101.3968 -140.208 90)
		(property "Reference" "C2A14"
			(at 1.848866 0.752348 90)
			(unlocked yes)
			(layer "F.SilkS")
			(effects
				(font
					(size 1.27 0.9652)
					(thickness 0.1524)
				)
			)
		)
		(property "Value" ""
			(at 0 0 90)
			(layer "F.Fab")
			(effects
				(font
					(size 1.27 1.27)
				)
			)
		)
		(duplicate_pad_numbers_are_jumpers no)
		(fp_rect
			(start -0.500126 1.598422)
			(end 0.500126 -0.201422)
			(stroke
				(width 0)
				(type default)
			)
			(fill no)
			(layer "F.CrtYd")
		)
		(fp_line
			(start 0.500126 -0.201422)
			(end 0.500126 1.598422)
			(stroke
				(width 0.1)
				(type default)
			)
			(layer "F.Fab")
		)
		(fp_line
			(start -0.500126 -0.201422)
			(end 0.500126 -0.201422)
			(stroke
				(width 0.1)
				(type default)
			)
			(layer "F.Fab")
		)
		(fp_line
			(start 0.500126 1.598422)
			(end -0.500126 1.598422)
			(stroke
				(width 0.1)
				(type default)
			)
			(layer "F.Fab")
		)
		(fp_line
			(start -0.500126 1.598422)
			(end -0.500126 -0.201422)
			(stroke
				(width 0.1)
				(type default)
			)
			(layer "F.Fab")
		)
		(pad "1" smd rect
			(at 0 0)
			(size 0.889 0.9906)
			(layers "F.Cu" "F.Mask" "F.Paste")
			(net "PVDDQ_KLM")
		)
		(pad "2" smd rect
			(at 0 1.397)
			(size 0.889 0.9906)
			(layers "F.Cu" "F.Mask" "F.Paste")
			(net "GND")
		)
		(zone
			(layer "F.Cu")
			(hatch none 0.5)
			(connect_pads
				(clearance 0)
			)
			(min_thickness 0.25)
			(keepout
				(tracks not_allowed)
				(vias allowed)
				(pads allowed)
				(copperpour not_allowed)
				(footprints allowed)
			)
			(placement
				(enabled no)
				(sheetname "")
			)
			(fill
				(thermal_gap 0.5)
				(thermal_bridge_width 0.5)
				(island_removal_mode 0)
			)
			(polygon
				(pts
					(xy 102.3493 -139.7127) (xy 102.3493 -140.7033) (xy 101.8413 -140.7033) (xy 101.8413 -139.7127)
				)
			)
		)
		(zone
			(layer "F.Cu")
			(hatch none 0.5)
			(connect_pads
				(clearance 0)
			)
			(min_thickness 0.25)
			(keepout
				(tracks allowed)
				(vias not_allowed)
				(pads allowed)
				(copperpour not_allowed)
				(footprints allowed)
			)
			(placement
				(enabled no)
				(sheetname "")
			)
			(fill
				(thermal_gap 0.5)
				(thermal_bridge_width 0.5)
				(island_removal_mode 0)
			)
			(polygon
				(pts
					(xy 102.3493 -139.7127) (xy 102.3493 -140.7033) (xy 101.8413 -140.7033) (xy 101.8413 -139.7127)
				)
			)
		)
	)
	(footprint ""
		(layer "F.Cu")
		(at 14.097 10.7315 -90)
		(property "Reference" "T1P26"
			(at 0 0 270)
			(layer "F.SilkS")
			(hide yes)
			(effects
				(font
					(size 1.27 1.27)
				)
			)
		)
		(property "Value" "*"
			(at 0 -3.44805 270)
			(unlocked yes)
			(layer "F.Fab")
			(hide yes)
			(effects
				(font
					(size 0.889 0.889)
					(thickness 0.1524)
				)
			)
		)
		(property "Device Type" "TPAD-SE-2P-GP_DISCRET-GA1-TPADA"
			(at 0 -4.97205 270)
			(unlocked yes)
			(layer "F.Fab")
			(hide yes)
			(effects
				(font
					(size 0.889 0.889)
					(thickness 0.1524)
				)
			)
		)
		(duplicate_pad_numbers_are_jumpers no)
		(fp_line
			(start -1.016 2.286)
			(end -1.016 -2.286)
			(stroke
				(width 0.1524)
				(type default)
			)
			(layer "F.SilkS")
		)
		(fp_line
			(start 1.016 2.286)
			(end -1.016 2.286)
			(stroke
				(width 0.1524)
				(type default)
			)
			(layer "F.SilkS")
		)
		(fp_line
			(start -1.016 -2.286)
			(end 1.016 -2.286)
			(stroke
				(width 0.1524)
				(type default)
			)
			(layer "F.SilkS")
		)
		(fp_line
			(start 1.016 -2.286)
			(end 1.016 2.286)
			(stroke
				(width 0.1524)
				(type default)
			)
			(layer "F.SilkS")
		)
		(fp_rect
			(start -1.27 2.54)
			(end 1.27 -2.54)
			(stroke
				(width 0)
				(type default)
			)
			(fill no)
			(layer "F.CrtYd")
		)
		(fp_rect
			(start -1.27 2.54)
			(end 1.27 -2.54)
			(stroke
				(width 0)
				(type default)
			)
			(fill no)
			(layer "F.Fab")
		)
		(pad "1" thru_hole circle
			(at 0 -1.27 270)
			(size 1.524 1.524)
			(drill 0.9144)
			(layers "*.Cu" "*.Mask")
			(remove_unused_layers no)
			(net "L3_40OHM_6INCH")
			(clearance -0.0508)
			(thermal_gap 0.127)
			(padstack
				(mode front_inner_back)
				(layer "Inner"
					(shape circle)
					(size 1.1684 1.1684)
					(clearance 0.127)
				)
				(layer "B.Cu"
					(shape circle)
					(size 1.524 1.524)
					(clearance -0.0508)
				)
			)
		)
		(pad "GND1" thru_hole rect
			(at 0 1.27 270)
			(size 1.524 1.524)
			(drill 0.9144)
			(layers "*.Cu" "*.Mask")
			(remove_unused_layers no)
			(net "GND")
			(clearance -0.0508)
			(thermal_gap 0.127)
			(padstack
				(mode front_inner_back)
				(layer "Inner"
					(shape circle)
					(size 1.1684 1.1684)
					(clearance 0.127)
				)
				(layer "B.Cu"
					(shape rect)
					(size 1.524 1.524)
					(clearance -0.0508)
				)
			)
		)
	)
)
